# S9S_MB_2U (Grand Teton) — schematic netlist excerpt (pin names and nets, part order shuffled) for the footprints in the layout excerpt that follows; sources: Cadence DE-HDL packaged netlist, KiCad conversion of 03242023_DA0F0TMBIJ0_F0T_Motherboard_J_brd_V01_OCP.brd

PC2949  Q_CAP  2.2UF 10V 10% X6S  pkg C0402  page 293 : A = PVCCFA_EHV_CPU1_PVCC ; B = GND
R4564  Q_RES  10K 1% CHIP  pkg 0402LF  page 184 : A = PD_GPP_I_14 ; B = GND

(kicad_pcb
	(version 20260206)
	(generator "pcbnew")
	(generator_version "10.0")
	(general
		(thickness 1.6)
		(legacy_teardrops no)
	)
	(paper "A4")
	(title_block
		(title "03242023_DA0F0TMBIJ0_F0T_Motherboard_J_brd_V01_OCP.brd")
		(comment 1 "Grand Teton / footprints 2046-2047 of 6105")
	)
	(layers
		(0 "F.Cu" signal "TOP")
		(4 "In1.Cu" signal "GND")
		(6 "In2.Cu" signal "IN1")
		(8 "In3.Cu" signal "GND1")
		(10 "In4.Cu" signal "IN2")
		(12 "In5.Cu" signal "GND2")
		(14 "In6.Cu" signal "IN3")
		(16 "In7.Cu" signal "GND3")
		(18 "In8.Cu" signal "VCC")
		(20 "In9.Cu" signal "VCC1")
		(22 "In10.Cu" signal "GND4")
		(24 "In11.Cu" signal "IN4")
		(26 "In12.Cu" signal "GND5")
		(28 "In13.Cu" signal "IN5")
		(30 "In14.Cu" signal "GND6")
		(32 "In15.Cu" signal "IN6")
		(34 "In16.Cu" signal "GND7")
		(2 "B.Cu" signal "BOTTOM")
		(9 "F.Adhes" user "F.Adhesive")
		(11 "B.Adhes" user "B.Adhesive")
		(13 "F.Paste" user "Package Geometry/Pastemask Top")
		(15 "B.Paste" user "Package Geometry/Pastemask Bottom")
		(5 "F.SilkS" user "Ref Des/Silkscreen Top")
		(7 "B.SilkS" user "Ref Des/Silkscreen Bottom")
		(1 "F.Mask" user "Board Geometry/Soldermask Top")
		(3 "B.Mask" user "Board Geometry/Soldermask Bottom")
		(17 "Dwgs.User" user "User.Drawings")
		(19 "Cmts.User" user "User.Comments")
		(21 "Eco1.User" user "User.Eco1")
		(23 "Eco2.User" user "User.Eco2")
		(25 "Edge.Cuts" user "Board Geometry/Outline")
		(27 "Margin" user)
		(31 "F.CrtYd" user "Package Geometry/Place Bound Top")
		(29 "B.CrtYd" user "Package Geometry/Place Bound Bottom")
		(35 "F.Fab" user "Ref Des/Assembly Top")
		(33 "B.Fab" user "Ref Des/Assembly Bottom")
	)
	(footprint ""
		(layer "F.Cu")
		(at 55.090314 -144.267174)
		(property "Reference" "PC2949"
			(at 0 0 0)
			(layer "F.SilkS")
			(hide yes)
			(effects
				(font
					(size 1.27 1.27)
				)
			)
		)
		(property "Value" ""
			(at 0 0 0)
			(layer "F.Fab")
			(effects
				(font
					(size 1.27 1.27)
				)
			)
		)
		(duplicate_pad_numbers_are_jumpers no)
		(fp_line
			(start -0.7874 -0.4064)
			(end 0.7874 -0.4064)
			(stroke
				(width 0.1524)
				(type default)
			)
			(layer "F.SilkS")
		)
		(fp_line
			(start -0.7874 0.4064)
			(end -0.7874 -0.4064)
			(stroke
				(width 0.1524)
				(type default)
			)
			(layer "F.SilkS")
		)
		(fp_line
			(start 0.7874 -0.4064)
			(end 0.7874 0.4064)
			(stroke
				(width 0.1524)
				(type default)
			)
			(layer "F.SilkS")
		)
		(fp_line
			(start 0.7874 0.4064)
			(end -0.7874 0.4064)
			(stroke
				(width 0.1524)
				(type default)
			)
			(layer "F.SilkS")
		)
		(fp_line
			(start -0.67945 -0.305054)
			(end -0.12065 -0.305054)
			(stroke
				(width 0.1)
				(type default)
			)
			(layer "F.Fab")
		)
		(fp_line
			(start -0.67945 0.3048)
			(end -0.67945 -0.305054)
			(stroke
				(width 0.1)
				(type default)
			)
			(layer "F.Fab")
		)
		(fp_line
			(start -0.12065 -0.305054)
			(end -0.12065 -0.2794)
			(stroke
				(width 0.1)
				(type default)
			)
			(layer "F.Fab")
		)
		(fp_line
			(start -0.12065 -0.2794)
			(end 0.12065 -0.2794)
			(stroke
				(width 0.1)
				(type default)
			)
			(layer "F.Fab")
		)
		(fp_line
			(start -0.12065 0.2794)
			(end -0.12065 0.3048)
			(stroke
				(width 0.1)
				(type default)
			)
			(layer "F.Fab")
		)
		(fp_line
			(start -0.12065 0.3048)
			(end -0.67945 0.3048)
			(stroke
				(width 0.1)
				(type default)
			)
			(layer "F.Fab")
		)
		(fp_line
			(start 0.120396 0.2794)
			(end -0.12065 0.2794)
			(stroke
				(width 0.1)
				(type default)
			)
			(layer "F.Fab")
		)
		(fp_line
			(start 0.120396 0.3048)
			(end 0.120396 0.2794)
			(stroke
				(width 0.1)
				(type default)
			)
			(layer "F.Fab")
		)
		(fp_line
			(start 0.12065 -0.3048)
			(end 0.67945 -0.3048)
			(stroke
				(width 0.1)
				(type default)
			)
			(layer "F.Fab")
		)
		(fp_line
			(start 0.12065 -0.2794)
			(end 0.12065 -0.3048)
			(stroke
				(width 0.1)
				(type default)
			)
			(layer "F.Fab")
		)
		(fp_line
			(start 0.67945 -0.3048)
			(end 0.67945 0.3048)
			(stroke
				(width 0.1)
				(type default)
			)
			(layer "F.Fab")
		)
		(fp_line
			(start 0.67945 0.3048)
			(end 0.120396 0.3048)
			(stroke
				(width 0.1)
				(type default)
			)
			(layer "F.Fab")
		)
		(pad "1" smd circle
			(at -0.40005 0)
			(size 0 0)
			(layers "F.Cu" "F.Mask" "F.Paste")
			(net "PVCCFA_EHV_CPU1_PVCC")
		)
		(pad "2" smd circle
			(at 0.40005 0)
			(size 0 0)
			(layers "F.Cu" "F.Mask" "F.Paste")
			(net "GND")
		)
	)
	(footprint ""
		(layer "F.Cu")
		(at 314.03544 -62.060328 180)
		(property "Reference" "R4564"
			(at 0 0 180)
			(layer "F.SilkS")
			(hide yes)
			(effects
				(font
					(size 1.27 1.27)
				)
			)
		)
		(property "Value" ""
			(at 0 0 180)
			(layer "F.Fab")
			(effects
				(font
					(size 1.27 1.27)
				)
			)
		)
		(duplicate_pad_numbers_are_jumpers no)
		(fp_line
			(start 0.7874 0.4064)
			(end -0.7874 0.4064)
			(stroke
				(width 0.1524)
				(type default)
			)
			(layer "F.SilkS")
		)
		(fp_line
			(start 0.7874 -0.4064)
			(end 0.7874 0.4064)
			(stroke
				(width 0.1524)
				(type default)
			)
			(layer "F.SilkS")
		)
		(fp_line
			(start -0.7874 0.4064)
			(end -0.7874 -0.4064)
			(stroke
				(width 0.1524)
				(type default)
			)
			(layer "F.SilkS")
		)
		(fp_line
			(start -0.7874 -0.4064)
			(end 0.7874 -0.4064)
			(stroke
				(width 0.1524)
				(type default)
			)
			(layer "F.SilkS")
		)
		(fp_line
			(start 0.67945 0.3048)
			(end 0.120396 0.3048)
			(stroke
				(width 0.1)
				(type default)
			)
			(layer "F.Fab")
		)
		(fp_line
			(start 0.67945 -0.3048)
			(end 0.67945 0.3048)
			(stroke
				(width 0.1)
				(type default)
			)
			(layer "F.Fab")
		)
		(fp_line
			(start 0.12065 -0.2794)
			(end 0.12065 -0.3048)
			(stroke
				(width 0.1)
				(type default)
			)
			(layer "F.Fab")
		)
		(fp_line
			(start 0.12065 -0.3048)
			(end 0.67945 -0.3048)
			(stroke
				(width 0.1)
				(type default)
			)
			(layer "F.Fab")
		)
		(fp_line
			(start 0.120396 0.3048)
			(end 0.120396 0.2794)
			(stroke
				(width 0.1)
				(type default)
			)
			(layer "F.Fab")
		)
		(fp_line
			(start 0.120396 0.2794)
			(end -0.12065 0.2794)
			(stroke
				(width 0.1)
				(type default)
			)
			(layer "F.Fab")
		)
		(fp_line
			(start -0.12065 0.3048)
			(end -0.67945 0.3048)
			(stroke
				(width 0.1)
				(type default)
			)
			(layer "F.Fab")
		)
		(fp_line
			(start -0.12065 0.2794)
			(end -0.12065 0.3048)
			(stroke
				(width 0.1)
				(type default)
			)
			(layer "F.Fab")
		)
		(fp_line
			(start -0.12065 -0.2794)
			(end 0.12065 -0.2794)
			(stroke
				(width 0.1)
				(type default)
			)
			(layer "F.Fab")
		)
		(fp_line
			(start -0.12065 -0.305054)
			(end -0.12065 -0.2794)
			(stroke
				(width 0.1)
				(type default)
			)
			(layer "F.Fab")
		)
		(fp_line
			(start -0.67945 0.3048)
			(end -0.67945 -0.305054)
			(stroke
				(width 0.1)
				(type default)
			)
			(layer "F.Fab")
		)
		(fp_line
			(start -0.67945 -0.305054)
			(end -0.12065 -0.305054)
			(stroke
				(width 0.1)
				(type default)
			)
			(layer "F.Fab")
		)
		(pad "1" smd circle
			(at -0.40005 0 180)
			(size 0 0)
			(layers "F.Cu" "F.Mask" "F.Paste")
			(net "PD_GPP_I_14")
		)
		(pad "2" smd circle
			(at 0.40005 0 180)
			(size 0 0)
			(layers "F.Cu" "F.Mask" "F.Paste")
			(net "GND")
		)
	)
)
